# T6G (Grand Teton) — schematic parts with pin connectivity, parts 912–1048 of 8303; source: Cadence DE-HDL packaged netlist (pstxprt.dat, pstxnet.dat, pstchip.dat)

C911  Q_CAP_DIFFBUS  DIFF BUS_0.22UF 6.3V 20% X6S  pkg C0201  page 63 : 1 = P5E_CPU0_P0_TX_C_DP<11> ; 2 = P5E_CPU0_P0_TX_DP<11>
C912  Q_CAP_DIFFBUS  DIFF BUS_0.22UF 6.3V 20% X6S  pkg C0201  page 63 : 1 = P5E_CPU0_P0_TX_C_DN<10> ; 2 = P5E_CPU0_P0_TX_DN<10>
C913  Q_CAP_DIFFBUS  DIFF BUS_0.22UF 6.3V 20% X6S  pkg C0201  page 63 : 1 = P5E_CPU0_P0_TX_C_DP<10> ; 2 = P5E_CPU0_P0_TX_DP<10>
C914  Q_CAP_DIFFBUS  DIFF BUS_0.22UF 6.3V 20% X6S  pkg C0201  page 63 : 1 = P5E_CPU0_P0_TX_C_DN<9> ; 2 = P5E_CPU0_P0_TX_DN<9>
C915  Q_CAP_DIFFBUS  DIFF BUS_0.22UF 6.3V 20% X6S  pkg C0201  page 63 : 1 = P5E_CPU0_P0_TX_C_DP<9> ; 2 = P5E_CPU0_P0_TX_DP<9>
C916  Q_CAP_DIFFBUS  DIFF BUS_0.22UF 6.3V 20% X6S  pkg C0201  page 63 : 1 = P5E_CPU0_P0_TX_C_DN<8> ; 2 = P5E_CPU0_P0_TX_DN<8>
C917  Q_CAP_DIFFBUS  DIFF BUS_0.22UF 6.3V 20% X6S  pkg C0201  page 63 : 1 = P5E_CPU0_P0_TX_C_DP<8> ; 2 = P5E_CPU0_P0_TX_DP<8>
C918  Q_CAP_DIFFBUS  DIFF BUS_0.22UF 6.3V 20% X6S  pkg C0201  page 63 : 1 = P5E_CPU0_P0_TX_C_DN<7> ; 2 = P5E_CPU0_P0_TX_DN<7>
C919  Q_CAP_DIFFBUS  DIFF BUS_0.22UF 6.3V 20% X6S  pkg C0201  page 63 : 1 = P5E_CPU0_P0_TX_C_DP<7> ; 2 = P5E_CPU0_P0_TX_DP<7>
C920  Q_CAP_DIFFBUS  DIFF BUS_0.22UF 6.3V 20% X6S  pkg C0201  page 63 : 1 = P5E_CPU0_P0_TX_C_DN<6> ; 2 = P5E_CPU0_P0_TX_DN<6>
C921  Q_CAP_DIFFBUS  DIFF BUS_0.22UF 6.3V 20% X6S  pkg C0201  page 63 : 1 = P5E_CPU0_P0_TX_C_DP<6> ; 2 = P5E_CPU0_P0_TX_DP<6>
C922  Q_CAP_DIFFBUS  DIFF BUS_0.22UF 6.3V 20% X6S  pkg C0201  page 63 : 1 = P5E_CPU0_P0_TX_C_DN<5> ; 2 = P5E_CPU0_P0_TX_DN<5>
C923  Q_CAP_DIFFBUS  DIFF BUS_0.22UF 6.3V 20% X6S  pkg C0201  page 63 : 1 = P5E_CPU0_P0_TX_C_DP<5> ; 2 = P5E_CPU0_P0_TX_DP<5>
C924  Q_CAP_DIFFBUS  DIFF BUS_0.22UF 6.3V 20% X6S  pkg C0201  page 63 : 1 = P5E_CPU0_P0_TX_C_DN<4> ; 2 = P5E_CPU0_P0_TX_DN<4>
C925  Q_CAP_DIFFBUS  DIFF BUS_0.22UF 6.3V 20% X6S  pkg C0201  page 63 : 1 = P5E_CPU0_P0_TX_C_DP<4> ; 2 = P5E_CPU0_P0_TX_DP<4>
C926  Q_CAP_DIFFBUS  DIFF BUS_0.22UF 6.3V 20% X6S  pkg C0201  page 63 : 1 = P5E_CPU0_P0_TX_C_DN<3> ; 2 = P5E_CPU0_P0_TX_DN<3>
C927  Q_CAP_DIFFBUS  DIFF BUS_0.22UF 6.3V 20% X6S  pkg C0201  page 63 : 1 = P5E_CPU0_P0_TX_C_DP<3> ; 2 = P5E_CPU0_P0_TX_DP<3>
C928  Q_CAP_DIFFBUS  DIFF BUS_0.22UF 6.3V 20% X6S  pkg C0201  page 63 : 1 = P5E_CPU0_P0_TX_C_DN<2> ; 2 = P5E_CPU0_P0_TX_DN<2>
C929  Q_CAP_DIFFBUS  DIFF BUS_0.22UF 6.3V 20% X6S  pkg C0201  page 63 : 1 = P5E_CPU0_P0_TX_C_DP<2> ; 2 = P5E_CPU0_P0_TX_DP<2>
C930  Q_CAP_DIFFBUS  DIFF BUS_0.22UF 6.3V 20% X6S  pkg C0201  page 63 : 1 = P5E_CPU0_P0_TX_C_DN<1> ; 2 = P5E_CPU0_P0_TX_DN<1>
C931  Q_CAP_DIFFBUS  DIFF BUS_0.22UF 6.3V 20% X6S  pkg C0201  page 63 : 1 = P5E_CPU0_P0_TX_C_DP<1> ; 2 = P5E_CPU0_P0_TX_DP<1>
C932  Q_CAP_DIFFBUS  DIFF BUS_0.22UF 6.3V 20% X6S  pkg C0201  page 63 : 1 = P5E_CPU0_P0_TX_C_DN<0> ; 2 = P5E_CPU0_P0_TX_DN<0>
C933  Q_CAP_DIFFBUS  DIFF BUS_0.22UF 6.3V 20% X6S  pkg C0201  page 63 : 1 = P5E_CPU0_P0_TX_C_DP<0> ; 2 = P5E_CPU0_P0_TX_DP<0>
C934  Q_CAP_DIFFBUS  DIFF BUS_0.22UF 6.3V 20% X6S  pkg C0201  page 63 : 1 = P5E_CPU0_P1_TX_C_DN<15> ; 2 = P5E_CPU0_P1_TX_DN<15>
C935  Q_CAP_DIFFBUS  DIFF BUS_0.22UF 6.3V 20% X6S  pkg C0201  page 63 : 1 = P5E_CPU0_P1_TX_C_DP<15> ; 2 = P5E_CPU0_P1_TX_DP<15>
C936  Q_CAP_DIFFBUS  DIFF BUS_0.22UF 6.3V 20% X6S  pkg C0201  page 63 : 1 = P5E_CPU0_P1_TX_C_DN<14> ; 2 = P5E_CPU0_P1_TX_DN<14>
C937  Q_CAP_DIFFBUS  DIFF BUS_0.22UF 6.3V 20% X6S  pkg C0201  page 63 : 1 = P5E_CPU0_P1_TX_C_DP<14> ; 2 = P5E_CPU0_P1_TX_DP<14>
C938  Q_CAP_DIFFBUS  DIFF BUS_0.22UF 6.3V 20% X6S  pkg C0201  page 63 : 1 = P5E_CPU0_P1_TX_C_DN<13> ; 2 = P5E_CPU0_P1_TX_DN<13>
C939  Q_CAP_DIFFBUS  DIFF BUS_0.22UF 6.3V 20% X6S  pkg C0201  page 63 : 1 = P5E_CPU0_P1_TX_C_DP<13> ; 2 = P5E_CPU0_P1_TX_DP<13>
C940  Q_CAP_DIFFBUS  DIFF BUS_0.22UF 6.3V 20% X6S  pkg C0201  page 63 : 1 = P5E_CPU0_P1_TX_C_DN<12> ; 2 = P5E_CPU0_P1_TX_DN<12>
C941  Q_CAP_DIFFBUS  DIFF BUS_0.22UF 6.3V 20% X6S  pkg C0201  page 63 : 1 = P5E_CPU0_P1_TX_C_DP<12> ; 2 = P5E_CPU0_P1_TX_DP<12>
C942  Q_CAP_DIFFBUS  DIFF BUS_0.22UF 6.3V 20% X6S  pkg C0201  page 63 : 1 = P5E_CPU0_P1_TX_C_DN<11> ; 2 = P5E_CPU0_P1_TX_DN<11>
C943  Q_CAP_DIFFBUS  DIFF BUS_0.22UF 6.3V 20% X6S  pkg C0201  page 63 : 1 = P5E_CPU0_P1_TX_C_DP<11> ; 2 = P5E_CPU0_P1_TX_DP<11>
C944  Q_CAP_DIFFBUS  DIFF BUS_0.22UF 6.3V 20% X6S  pkg C0201  page 63 : 1 = P5E_CPU0_P1_TX_C_DN<10> ; 2 = P5E_CPU0_P1_TX_DN<10>
C945  Q_CAP_DIFFBUS  DIFF BUS_0.22UF 6.3V 20% X6S  pkg C0201  page 63 : 1 = P5E_CPU0_P1_TX_C_DP<10> ; 2 = P5E_CPU0_P1_TX_DP<10>
C946  Q_CAP_DIFFBUS  DIFF BUS_0.22UF 6.3V 20% X6S  pkg C0201  page 63 : 1 = P5E_CPU0_P1_TX_C_DN<9> ; 2 = P5E_CPU0_P1_TX_DN<9>
C947  Q_CAP_DIFFBUS  DIFF BUS_0.22UF 6.3V 20% X6S  pkg C0201  page 63 : 1 = P5E_CPU0_P1_TX_C_DP<9> ; 2 = P5E_CPU0_P1_TX_DP<9>
C948  Q_CAP_DIFFBUS  DIFF BUS_0.22UF 6.3V 20% X6S  pkg C0201  page 63 : 1 = P5E_CPU0_P1_TX_C_DN<8> ; 2 = P5E_CPU0_P1_TX_DN<8>
C949  Q_CAP_DIFFBUS  DIFF BUS_0.22UF 6.3V 20% X6S  pkg C0201  page 63 : 1 = P5E_CPU0_P1_TX_C_DP<8> ; 2 = P5E_CPU0_P1_TX_DP<8>
C950  Q_CAP_DIFFBUS  DIFF BUS_0.22UF 6.3V 20% X6S  pkg C0201  page 63 : 1 = P5E_CPU0_P1_TX_C_DN<7> ; 2 = P5E_CPU0_P1_TX_DN<7>
C951  Q_CAP_DIFFBUS  DIFF BUS_0.22UF 6.3V 20% X6S  pkg C0201  page 63 : 1 = P5E_CPU0_P1_TX_C_DP<7> ; 2 = P5E_CPU0_P1_TX_DP<7>
C952  Q_CAP_DIFFBUS  DIFF BUS_0.22UF 6.3V 20% X6S  pkg C0201  page 63 : 1 = P5E_CPU0_P1_TX_C_DN<6> ; 2 = P5E_CPU0_P1_TX_DN<6>
C953  Q_CAP_DIFFBUS  DIFF BUS_0.22UF 6.3V 20% X6S  pkg C0201  page 63 : 1 = P5E_CPU0_P1_TX_C_DP<6> ; 2 = P5E_CPU0_P1_TX_DP<6>
C954  Q_CAP_DIFFBUS  DIFF BUS_0.22UF 6.3V 20% X6S  pkg C0201  page 63 : 1 = P5E_CPU0_P1_TX_C_DN<5> ; 2 = P5E_CPU0_P1_TX_DN<5>
C955  Q_CAP_DIFFBUS  DIFF BUS_0.22UF 6.3V 20% X6S  pkg C0201  page 63 : 1 = P5E_CPU0_P1_TX_C_DP<5> ; 2 = P5E_CPU0_P1_TX_DP<5>
C956  Q_CAP_DIFFBUS  DIFF BUS_0.22UF 6.3V 20% X6S  pkg C0201  page 63 : 1 = P5E_CPU0_P1_TX_C_DN<4> ; 2 = P5E_CPU0_P1_TX_DN<4>
C957  Q_CAP_DIFFBUS  DIFF BUS_0.22UF 6.3V 20% X6S  pkg C0201  page 63 : 1 = P5E_CPU0_P1_TX_C_DP<4> ; 2 = P5E_CPU0_P1_TX_DP<4>
C958  Q_CAP_DIFFBUS  DIFF BUS_0.22UF 6.3V 20% X6S  pkg C0201  page 63 : 1 = P5E_CPU0_P1_TX_C_DN<3> ; 2 = P5E_CPU0_P1_TX_DN<3>
C959  Q_CAP_DIFFBUS  DIFF BUS_0.22UF 6.3V 20% X6S  pkg C0201  page 63 : 1 = P5E_CPU0_P1_TX_C_DP<3> ; 2 = P5E_CPU0_P1_TX_DP<3>
C960  Q_CAP_DIFFBUS  DIFF BUS_0.22UF 6.3V 20% X6S  pkg C0201  page 63 : 1 = P5E_CPU0_P1_TX_C_DN<2> ; 2 = P5E_CPU0_P1_TX_DN<2>
C961  Q_CAP_DIFFBUS  DIFF BUS_0.22UF 6.3V 20% X6S  pkg C0201  page 63 : 1 = P5E_CPU0_P1_TX_C_DP<2> ; 2 = P5E_CPU0_P1_TX_DP<2>
C962  Q_CAP_DIFFBUS  DIFF BUS_0.22UF 6.3V 20% X6S  pkg C0201  page 63 : 1 = P5E_CPU0_P1_TX_C_DN<1> ; 2 = P5E_CPU0_P1_TX_DN<1>
C963  Q_CAP_DIFFBUS  DIFF BUS_0.22UF 6.3V 20% X6S  pkg C0201  page 63 : 1 = P5E_CPU0_P1_TX_C_DP<1> ; 2 = P5E_CPU0_P1_TX_DP<1>
C964  Q_CAP_DIFFBUS  DIFF BUS_0.22UF 6.3V 20% X6S  pkg C0201  page 63 : 1 = P5E_CPU0_P1_TX_C_DN<0> ; 2 = P5E_CPU0_P1_TX_DN<0>
C965  Q_CAP_DIFFBUS  DIFF BUS_0.22UF 6.3V 20% X6S  pkg C0201  page 63 : 1 = P5E_CPU0_P1_TX_C_DP<0> ; 2 = P5E_CPU0_P1_TX_DP<0>
C966  Q_CAP  100UF 4V 20% X6S  pkg C0805  page 301 : 1 = P0V9_CPU0_RT2_2A ; 2 = GND
C967  Q_CAP  4.7UF 6.3V 20% X6S  pkg 0402  page 301 : 1 = P0V9_CPU0_RT2_2A ; 2 = GND
C968  Q_CAP  0.1UF 10V 10% X7S  pkg C0201  page 301 : 1 = P0V9_CPU0_RT2_2A ; 2 = GND
C969  Q_CAP  22UF 4V 20% X6S  pkg C0402  page 301 : 1 = P0V9_CPU0_RT2_2A ; 2 = GND
C970  Q_CAP  4.7UF 6.3V 20% X6S  pkg 0402  page 301 : 1 = P0V9_CPU0_RT2_2A ; 2 = GND
C971  Q_CAP  10UF 6.3V 20% X6S  pkg C0402  page 301 : 1 = P0V9_CPU0_RT_2D ; 2 = GND
C972  Q_CAP  0.1UF 10V 10% X7S  pkg C0201  page 301 : 1 = P0V9_CPU0_RT2_2A ; 2 = GND
C973  Q_CAP  10UF 6.3V 20% X6S  pkg C0402  page 301 : 1 = P0V9_CPU0_RT2_2A ; 2 = GND
C974  Q_CAP  22UF 4V 20% X6S  pkg C0402  page 301 : 1 = P0V9_CPU0_RT2_2A ; 2 = GND
C975  Q_CAP  1UF 4V 20% X6S  pkg 0201  page 301 : 1 = P0V9_CPU0_RT2_2A ; 2 = GND
C976  Q_CAP  4.7UF 6.3V 20% X6S  pkg 0402  page 301 : 1 = P0V9_CPU0_RT_2D ; 2 = GND
C977  Q_CAP  4.7UF 6.3V 20% X6S  pkg 0402  page 301 : 1 = P0V9_CPU0_RT2_2A ; 2 = GND
C978  Q_CAP  1UF 4V 20% X6S  pkg 0201  page 301 : 1 = P0V9_CPU0_RT2_2A ; 2 = GND
C979  Q_CAP  1UF 4V 20% X6S  pkg 0201  page 301 : 1 = P0V9_CPU0_RT2_2A ; 2 = GND
C980  Q_CAP  1UF 4V 20% X6S  pkg 0201  page 301 : 1 = P0V9_CPU0_RT_2D ; 2 = GND
C981  Q_CAP  4.7UF 6.3V 20% X6S  pkg 0402  page 301 : 1 = P0V9_CPU0_RT2_2A ; 2 = GND
C982  Q_CAP  0.1UF 10V 10% X7S  pkg C0201  page 301 : 1 = P0V9_CPU0_RT2_2A ; 2 = GND
C983  Q_CAP  1UF 4V 20% X6S  pkg 0201  page 301 : 1 = P0V9_CPU0_RT2_2A ; 2 = GND
C984  Q_CAP  0.1UF 10V 10% X7S  pkg C0201  page 301 : 1 = P0V9_CPU0_RT2_2A ; 2 = GND
C985  Q_CAP  0.1UF 10V 10% X7S  pkg C0201  page 301 : 1 = P0V9_CPU0_RT2_2A ; 2 = GND
C986  Q_CAP  10UF 6.3V 20% X6S  pkg C0402  page 301 : 1 = P0V9_CPU0_RT2_2A ; 2 = GND
C987  Q_CAP  0.1UF 10V 10% X7S  pkg C0201  page 301 : 1 = P0V9_CPU0_RT2_2A ; 2 = GND
C988  Q_CAP  22UF 4V 20% X6S  pkg C0402  page 301 : 1 = P0V9_CPU0_RT2_2A ; 2 = GND
C989  Q_CAP  0.1UF 10V 10% X7S  pkg C0201  page 300 : 1 = P1V8_CPU0_RT_1D ; 2 = GND
C990  Q_CAP  100UF 4V 20% X6S  pkg C0805  page 312 : 1 = P1V8_CPU0_RT_1D ; 2 = GND
C991  Q_CAP  100UF 4V 20% X6S  pkg C0805  page 312 : 1 = P1V8_CPU0_RT3_1A ; 2 = GND
C992  Q_CAP  22UF 4V 20% X6S  pkg C0402  page 312 : 1 = P1V8_CPU0_RT_1D ; 2 = GND
C993  Q_CAP  22UF 4V 20% X6S  pkg C0402  page 312 : 1 = P1V8_CPU0_RT3_1A ; 2 = GND
C994  Q_CAP  10UF 6.3V 20% X6S  pkg C0402  page 312 : 1 = P1V8_CPU0_RT_1D ; 2 = GND
C995  Q_CAP  10UF 6.3V 20% X6S  pkg C0402  page 312 : 1 = P1V8_CPU0_RT3_1A ; 2 = GND
C996  Q_CAP  4.7UF 6.3V 20% X6S  pkg 0402  page 312 : 1 = P1V8_CPU0_RT3_1A ; 2 = GND
C997  Q_CAP  4.7UF 6.3V 20% X6S  pkg 0402  page 312 : 1 = P1V8_CPU0_RT_1D ; 2 = GND
C998  Q_CAP  1UF 4V 20% X6S  pkg 0201  page 312 : 1 = P1V8_CPU0_RT3_1A ; 2 = GND
C999  Q_CAP  1UF 4V 20% X6S  pkg 0201  page 312 : 1 = P1V8_CPU0_RT3_1A_1D ; 2 = GND
C1000  Q_CAP  1UF 4V 20% X6S  pkg 0201  page 312 : 1 = P1V8_CPU0_RT3_1A ; 2 = GND
C1001  Q_CAP  0.1UF 10V 10% X7S  pkg C0201  page 312 : 1 = P1V8_CPU0_RT3_1A ; 2 = GND
C1002  Q_CAP  0.1UF 10V 10% X7S  pkg C0201  page 312 : 1 = P1V8_CPU0_RT3_1A_1D ; 2 = GND
C1003  Q_CAP  0.1UF 10V 10% X7S  pkg C0201  page 312 : 1 = P1V8_CPU0_RT3_1A ; 2 = GND
C1004  Q_CAP  0.1UF 10V 10% X7S  pkg C0201  page 312 : 1 = P1V8_CPU0_RT3_1A ; 2 = GND
C1005  Q_CAP  0.1UF 10V 10% X7S  pkg C0201  page 312 : 1 = P1V8_CPU0_RT3_1A ; 2 = GND
C1006  Q_CAP  1UF 4V 20% X6S  pkg 0201  page 312 : 1 = P0V9_CPU0_RT3_2A ; 2 = GND
C1007  Q_CAP  0.1UF 10V 10% X7S  pkg C0201  page 312 : 1 = P0V9_CPU0_RT_2D ; 2 = GND
C1008  Q_CAP  0.1UF 10V 10% X7S  pkg C0201  page 312 : 1 = P0V9_CPU0_RT3_2A ; 2 = GND
C1009  Q_CAP  0.1UF 10V 10% X7S  pkg C0201  page 312 : 1 = P0V9_CPU0_RT_2D ; 2 = GND
C1010  Q_CAP  0.1UF 10V 10% X7S  pkg C0201  page 312 : 1 = P0V9_CPU0_RT3_2A ; 2 = GND
C1011  Q_CAP  0.1UF 10V 10% X7S  pkg C0201  page 312 : 1 = P0V9_CPU0_RT3_2A ; 2 = GND
C1012  Q_CAP  0.1UF 10V 10% X7S  pkg C0201  page 312 : 1 = P0V9_CPU0_RT_2D ; 2 = GND
C1013  Q_CAP  1UF 4V 20% X6S  pkg 0201  page 312 : 1 = P0V9_CPU0_RT3_2A ; 2 = GND
C1014  Q_CAP  0.1UF 10V 10% X7S  pkg C0201  page 312 : 1 = P0V9_CPU0_RT3_2A_2D ; 2 = GND
C1015  Q_CAP  1UF 4V 20% X6S  pkg 0201  page 312 : 1 = P0V9_CPU0_RT3_2A ; 2 = GND
C1016  Q_CAP  1UF 4V 20% X6S  pkg 0201  page 312 : 1 = P0V9_CPU0_RT_2D ; 2 = GND
C1017  Q_CAP  1UF 4V 20% X6S  pkg 0201  page 312 : 1 = P0V9_CPU0_RT3_2A ; 2 = GND
C1018  Q_CAP  1UF 4V 20% X6S  pkg 0201  page 312 : 1 = P0V9_CPU0_RT3_2A_2D ; 2 = GND
C1019  Q_CAP  1UF 4V 20% X6S  pkg 0201  page 312 : 1 = P0V9_CPU0_RT3_2A ; 2 = GND
C1020  Q_CAP  1UF 4V 20% X6S  pkg 0201  page 312 : 1 = P0V9_CPU0_RT3_2A_2D ; 2 = GND
C1021  Q_CAP  0.1UF 10V 10% X7S  pkg C0201  page 312 : 1 = P0V9_CPU0_RT3_2A_2D ; 2 = GND
C1022  Q_CAP  100UF 4V 20% X6S  pkg C0805  page 312 : 1 = P0V9_CPU0_RT3_2A ; 2 = GND
C1023  Q_CAP  10UF 6.3V 20% X6S  pkg C0402  page 312 : 1 = P0V9_CPU0_RT3_2A ; 2 = GND
C1024  Q_CAP  1UF 4V 20% X6S  pkg 0201  page 312 : 1 = P0V9_CPU0_RT3_2A ; 2 = GND
C1025  Q_CAP  100UF 4V 20% X6S  pkg C0805  page 312 : 1 = P0V9_CPU0_RT3_2A ; 2 = GND
C1026  Q_CAP  22UF 4V 20% X6S  pkg C0402  page 312 : 1 = P0V9_CPU0_RT3_2A ; 2 = GND
C1027  Q_CAP  1UF 4V 20% X6S  pkg 0201  page 312 : 1 = P0V9_CPU0_RT3_2A ; 2 = GND
C1028  Q_CAP  100UF 4V 20% X6S  pkg C0805  page 312 : 1 = P0V9_CPU0_RT_2D ; 2 = GND
C1029  Q_CAP  100UF 4V 20% X6S  pkg C0805  page 312 : 1 = P0V9_CPU0_RT3_2A ; 2 = GND
C1030  Q_CAP  22UF 4V 20% X6S  pkg C0402  page 312 : 1 = P0V9_CPU0_RT3_2A ; 2 = GND
C1031  Q_CAP  1UF 4V 20% X6S  pkg 0201  page 312 : 1 = P0V9_CPU0_RT3_2A ; 2 = GND
C1032  Q_CAP  22UF 4V 20% X6S  pkg C0402  page 312 : 1 = P0V9_CPU0_RT_2D ; 2 = GND
C1033  Q_CAP  100UF 4V 20% X6S  pkg C0805  page 312 : 1 = P0V9_CPU0_RT3_2A ; 2 = GND
C1034  Q_CAP  4.7UF 6.3V 20% X6S  pkg 0402  page 312 : 1 = P0V9_CPU0_RT3_2A ; 2 = GND
C1035  Q_CAP  0.1UF 10V 10% X7S  pkg C0201  page 312 : 1 = P0V9_CPU0_RT3_2A ; 2 = GND
C1036  Q_CAP  10UF 6.3V 20% X6S  pkg C0402  page 312 : 1 = P0V9_CPU0_RT3_2A ; 2 = GND
C1037  Q_CAP  10UF 6.3V 20% X6S  pkg C0402  page 312 : 1 = P0V9_CPU0_RT3_2A ; 2 = GND
C1038  Q_CAP  4.7UF 6.3V 20% X6S  pkg 0402  page 312 : 1 = P0V9_CPU0_RT_2D ; 2 = GND
C1039  Q_CAP  1UF 4V 20% X6S  pkg 0201  page 312 : 1 = P0V9_CPU0_RT3_2A ; 2 = GND
C1040  Q_CAP  22UF 4V 20% X6S  pkg C0402  page 312 : 1 = P0V9_CPU0_RT3_2A ; 2 = GND
C1041  Q_CAP  22UF 4V 20% X6S  pkg C0402  page 312 : 1 = P0V9_CPU0_RT3_2A ; 2 = GND
C1042  Q_CAP  100NF 50V 10% X7R  pkg C0402  page 188 : 1 = P5V_AUX ; 2 = GND
C1043  Q_CAP  0.1UF 10V 10% X7S  pkg C0201  page 312 : 1 = P0V9_CPU0_RT3_2A ; 2 = GND
C1044  Q_CAP  10UF 6.3V 20% X6S  pkg C0402  page 312 : 1 = P0V9_CPU0_RT_2D ; 2 = GND
C1045  Q_CAP  4.7UF 6.3V 20% X6S  pkg 0402  page 312 : 1 = P0V9_CPU0_RT3_2A ; 2 = GND
C1046  Q_CAP  1UF 4V 20% X6S  pkg 0201  page 312 : 1 = P0V9_CPU0_RT3_2A ; 2 = GND
C1047  Q_CAP  0.1UF 10V 10% X7S  pkg C0201  page 312 : 1 = P0V9_CPU0_RT3_2A ; 2 = GND
